FILE_TYPE = CONNECTIVITY;
{Allegro Design Entry HDL 16.6-p007 (v16-6-112F) 10/10/2012}
"PAGE_NUMBER" = 217;
0"NC";
1"PVDDQ_ABC\g";
2"GND\g";
3"VR_FET_SW_P12V_STBY_PVDDQ_ABC\g";
4"GND\g";
5"P12V_STBY\g";
6"GND\g";
7"PVDDQ_ABC\g";
8"PVDDQ_ABC\g";
9"GND\g";
10"PVDDQ_ABC\g";
11"GND\g";
12"PVDDQ_ABC\g";
13"GND\g";
14"PVDDQ_ABC\g";
15"GND\g";
16"GND\g";
17"PVDDQ_ABC\g";
18"PVDDQ_ABC\g";
19"GND\g";
20"PVDDQ_ABC\g";
21"GND\g";
22"VSENSE_PVDDQ_ABC_P";
23"VSENSE_PVDDQ_ABC_N";
%"PVDDQ_ABC"
"1","(2900,2000)","0","mstr_symbols","I109";
;
HDL_POWER"PVDDQ_ABC"
VOLTAGE"1.2V"
BODY_TYPE"PLUMBING"
CDS_LIB"mstr_symbols";
"G\NAC"1;
%"CAP"
"1","(2875,2850)","0","mstr_discrete","I110";
;
CDS_SEC"1"
SEC"1"
SEC_TYPE"0805"
ROOM"VDDQ_ABC_PWR_VR"
CDS_LOCATION"C5G20"
BOM_COST"MEM_VRD_PVDDQ_CD"
CDS_LIB"mstr_discrete"
PART_NUMBER"602433-112"
VOLTAGE"4V"
VALUE"100UF"
LOCATION"C5G20"
TOLERANCE"20%"
PACK_TYPE"0805"
MATERIAL"X5R";
"A"
$PN"1"20;
"B"
$PN"2"21;
%"GND"
"1","(4625,1350)","0","mstr_symbols","I114";
;
HDL_POWER"GND"
VOLTAGE"0"
CDS_LIB"mstr_symbols"
SIZE"1B"
BODY_TYPE"PLUMBING"
BOM_COST"MEM_VRD_PVDDQ_CD"
ROOM"VDDQ_ABC_PWR_VR";
"A\NAC"2;
%"VCC_CORE"
"1","(200,1150)","0","mstr_symbols","I120";
;
CDS_LIB"mstr_symbols"
HDL_POWER"VR_FET_SW_P12V_STBY_PVDDQ_ABC";
"A"3;
%"GND"
"1","(200,475)","0","mstr_symbols","I123";
;
HDL_POWER"GND"
VOLTAGE"0"
CDS_LIB"mstr_symbols"
SIZE"1B"
BODY_TYPE"PLUMBING"
BOM_COST"MEM_VRD_PVDDQ_CD"
ROOM"VDDQ_ABC_PWR_VR";
"A\NAC"4;
%"INDUCTOR"
"1","(-225,900)","0","mstr_discrete","I124";
;
CDS_SEC"1"
BOM_COST"MEM_VRD_PVDDQ_CD"
SEC_TYPE"SM"
SEC"1"
ROOM"VDDQ_ABC_PWR_VR"
CDS_LIB"mstr_discrete"
CDS_LOCATION"L7F2"
PACK_TYPE"SM"
PART_NUMBER"D92183-020"
MATERIAL"IND"
LOCATION"L7F2"
VALUE"100NH";
"INA\NAC"
$PN"1"5;
"INB\NAC"
$PN"2"3;
%"CAPP"
"1","(200,700)","0","mstr_discrete","I175";
;
CDS_SEC"1"
SEC_TYPE"2626"
SEC"1"
ROOM"VDDQ_ABC_PWR_VR"
CDS_LOCATION"C7G2"
CDS_LIB"mstr_discrete"
PART_NUMBER"A31228-047"
LOCATION"C7G2"
VALUE"270UF"
TOLERANCE"20%"
PACK_TYPE"2626"
VOLTAGE"16V"
MATERIAL"OSCON";
"B"
$PN"2"4;
"A"
$PN"1"3;
%"P12V_STBY"
"1","(-550,1150)","0","mstr_symbols","I183";
;
SIZE"1B"
CDS_LIB"mstr_symbols"
BODY_TYPE"PLUMBING"
HDL_POWER"P12V_STBY"
VOLTAGE"12.0V";
"G\NAC"5;
%"CAP"
"1","(-1650,2850)","0","mstr_discrete","I184";
;
CDS_SEC"1"
SEC"1"
SEC_TYPE"0805LF"
BOM_COST"MEM_VRD_PVDDQ_ABC"
CDS_LOCATION"C5P39"
ROOM"VDDQ_ABC_CPU0"
VOLTAGE"4V"
CDS_LIB"mstr_discrete"
LOCATION"C5P39"
PART_NUMBER"C95333-002"
VALUE"22UF"
TOLERANCE"20%"
PACK_TYPE"0805LF"
MATERIAL"X6S";
"A"
$PN"1"7;
"B"
$PN"2"11;
%"CAP"
"1","(150,2825)","0","mstr_discrete","I186";
;
CDS_SEC"1"
SEC_TYPE"0603LF"
CDS_LIB"mstr_discrete"
BOM_COST"MEM_VRD_PVDDQ_ABC"
SEC"1"
CDS_LOCATION"C5D57"
ROOM"VDDQ_ABC_CPU0"
LOCATION"C5D57"
PART_NUMBER"E15431-001"
VALUE"10UF"
TOLERANCE"20%"
PACK_TYPE"0603LF"
MATERIAL"X6S"
VOLTAGE"4V";
"A"
$PN"1"10;
"B"
$PN"2"6;
%"GND"
"1","(150,2525)","0","mstr_symbols","I187";
;
HDL_POWER"GND"
VOLTAGE"0"
CDS_LIB"mstr_symbols"
BODY_TYPE"PLUMBING"
SIZE"1B"
BOM_COST"MEM_VRD_PVDDQ_CD"
ROOM"VDDQ_ABC_PWR_VR";
"A\NAC"6;
%"CAP"
"1","(-200,2850)","0","mstr_discrete","I188";
;
CDS_SEC"1"
SEC"1"
SEC_TYPE"0603LF"
ROOM"VDDQ_ABC_CPU0"
CDS_LOCATION"C5D56"
BOM_COST"MEM_VRD_PVDDQ_ABC"
CDS_LIB"mstr_discrete"
PART_NUMBER"E15431-001"
PACK_TYPE"0603LF"
LOCATION"C5D56"
VALUE"10UF"
VOLTAGE"4V"
TOLERANCE"20%"
MATERIAL"X6S";
"A"
$PN"1"10;
"B"
$PN"2"6;
%"CAP"
"1","(-550,2850)","0","mstr_discrete","I189";
;
CDS_SEC"1"
SEC"1"
SEC_TYPE"0603LF"
ROOM"VDDQ_ABC_CPU0"
CDS_LOCATION"C5D55"
BOM_COST"MEM_VRD_PVDDQ_ABC"
CDS_LIB"mstr_discrete"
PART_NUMBER"E15431-001"
LOCATION"C5D55"
VALUE"10UF"
TOLERANCE"20%"
PACK_TYPE"0603LF"
VOLTAGE"4V"
MATERIAL"X6S";
"A"
$PN"1"10;
"B"
$PN"2"6;
%"CAP"
"1","(-900,2850)","0","mstr_discrete","I190";
;
CDS_SEC"1"
SEC"1"
SEC_TYPE"0603LF"
ROOM"VDDQ_ABC_CPU0"
CDS_LOCATION"C5D54"
BOM_COST"MEM_VRD_PVDDQ_ABC"
CDS_LIB"mstr_discrete"
LOCATION"C5D54"
PART_NUMBER"E15431-001"
VALUE"10UF"
TOLERANCE"20%"
PACK_TYPE"0603LF"
MATERIAL"X6S"
VOLTAGE"4V";
"A"
$PN"1"10;
"B"
$PN"2"6;
%"PVDDQ_ABC"
"1","(-1650,3125)","0","mstr_symbols","I192";
;
ROOM"VDDQ_ABC_PWR_VR"
BOM_COST"MEM_VRD_PVDDQ_CD"
CDS_LIB"mstr_symbols"
BODY_TYPE"PLUMBING"
HDL_POWER"PVDDQ_ABC"
VOLTAGE"1.2V";
"G\NAC"7;
%"CAP"
"1","(-1300,2850)","0","mstr_discrete","I193";
;
CDS_SEC"1"
SEC"1"
SEC_TYPE"0805LF"
VOLTAGE"4V"
ROOM"VDDQ_ABC_CPU0"
CDS_LOCATION"C5P38"
BOM_COST"MEM_VRD_PVDDQ_ABC"
CDS_LIB"mstr_discrete"
PART_NUMBER"C95333-002"
MATERIAL"X6S"
PACK_TYPE"0805LF"
TOLERANCE"20%"
VALUE"22UF"
LOCATION"C5P38";
"A"
$PN"1"7;
"B"
$PN"2"11;
%"PVDDQ_ABC"
"1","(2925,1275)","0","mstr_symbols","I201";
;
HDL_POWER"PVDDQ_ABC"
CDS_LIB"mstr_symbols"
VOLTAGE"1.2V"
BODY_TYPE"PLUMBING";
"G\NAC"8;
%"GND"
"1","(3575,625)","0","mstr_symbols","I203";
;
SIZE"1B"
VOLTAGE"0"
HDL_POWER"GND"
BODY_TYPE"PLUMBING"
CDS_LIB"mstr_symbols"
BOM_COST"MEM_VRD_PVDDQ_CD";
"A\NAC"9;
%"CAP_A"
"1","(2925,1000)","0","dev_discrete","I205";
;
CDS_LOCATION"C5F2"
CDS_SEC"1"
SEC_TYPE"0603V"
SEC"1"
CDS_LIB"dev_discrete"
LOCATION"C5F2"
PART_NUMBER"602433-106"
VALUE"47UF"
PACK_TYPE"0603V"
VOLTAGE"4V"
MATERIAL"X5R"
TOLERANCE"20%";
"B"
$PN"2"9;
"A"
$PN"1"8;
%"CAP_A"
"1","(3275,1000)","0","dev_discrete","I206";
;
SEC"1"
SEC_TYPE"0603V"
CDS_SEC"1"
CDS_LOCATION"C5F1"
CDS_LIB"dev_discrete"
VALUE"47UF"
LOCATION"C5F1"
VOLTAGE"4V"
PART_NUMBER"602433-106"
TOLERANCE"20%"
PACK_TYPE"0603V"
MATERIAL"X5R";
"B"
$PN"2"9;
"A"
$PN"1"8;
%"CAP_A"
"1","(3675,1000)","0","dev_discrete","I207";
;
SEC"1"
SEC_TYPE"0603V"
CDS_SEC"1"
CDS_LOCATION"C5G10"
CDS_LIB"dev_discrete"
VALUE"47UF"
LOCATION"C5G10"
VOLTAGE"4V"
PART_NUMBER"602433-106"
PACK_TYPE"0603V"
TOLERANCE"20%"
MATERIAL"X5R";
"B"
$PN"2"9;
"A"
$PN"1"8;
%"CAP_A"
"1","(4000,1725)","0","dev_discrete","I208";
;
CDS_LOCATION"C5T2"
CDS_SEC"1"
SEC_TYPE"0603V"
SEC"1"
CDS_LIB"dev_discrete"
LOCATION"C5T2"
PART_NUMBER"602433-106"
VALUE"47UF"
TOLERANCE"20%"
PACK_TYPE"0603V"
VOLTAGE"4V"
MATERIAL"X5R";
"B"
$PN"2"2;
"A"
$PN"1"1;
%"CAP_A"
"1","(4350,1725)","0","dev_discrete","I209";
;
SEC"1"
SEC_TYPE"0603V"
CDS_SEC"1"
CDS_LOCATION"C5U11"
CDS_LIB"dev_discrete"
PART_NUMBER"602433-106"
LOCATION"C5U11"
VALUE"47UF"
TOLERANCE"20%"
VOLTAGE"4V"
MATERIAL"X5R"
PACK_TYPE"0603V";
"B"
$PN"2"2;
"A"
$PN"1"1;
%"CAP_A"
"1","(4750,1725)","0","dev_discrete","I210";
;
CDS_LOCATION"C5T13"
CDS_SEC"1"
SEC_TYPE"0603V"
SEC"1"
CDS_LIB"dev_discrete"
MATERIAL"X5R"
TOLERANCE"20%"
VALUE"47UF"
PART_NUMBER"602433-106"
LOCATION"C5T13"
VOLTAGE"4V"
PACK_TYPE"0603V";
"B"
$PN"2"2;
"A"
$PN"1"1;
%"CAP_A"
"1","(3650,1725)","0","dev_discrete","I211";
;
CDS_LOCATION"C5T4"
CDS_SEC"1"
SEC_TYPE"0603V"
SEC"1"
CDS_LIB"dev_discrete"
PART_NUMBER"602433-106"
LOCATION"C5T4"
VALUE"47UF"
MATERIAL"X5R"
VOLTAGE"4V"
TOLERANCE"20%"
PACK_TYPE"0603V";
"B"
$PN"2"2;
"A"
$PN"1"1;
%"CAP_A"
"1","(3250,1725)","0","dev_discrete","I212";
;
CDS_LOCATION"C5T1"
CDS_SEC"1"
SEC_TYPE"0603V"
SEC"1"
CDS_LIB"dev_discrete"
PART_NUMBER"602433-106"
TOLERANCE"20%"
VOLTAGE"4V"
MATERIAL"X5R"
VALUE"47UF"
LOCATION"C5T1"
PACK_TYPE"0603V";
"B"
$PN"2"2;
"A"
$PN"1"1;
%"CAP_A"
"1","(2900,1725)","0","dev_discrete","I213";
;
CDS_LOCATION"C5G19"
CDS_SEC"1"
SEC_TYPE"0603V"
SEC"1"
CDS_LIB"dev_discrete"
LOCATION"C5G19"
PART_NUMBER"602433-106"
PACK_TYPE"0603V"
VALUE"47UF"
TOLERANCE"20%"
VOLTAGE"4V"
MATERIAL"X5R";
"B"
$PN"2"2;
"A"
$PN"1"1;
%"PVDDQ_ABC"
"1","(-900,3125)","0","mstr_symbols","I214";
;
VOLTAGE"1.2V"
HDL_POWER"PVDDQ_ABC"
ROOM"VDDQ_ABC_PWR_VR"
BODY_TYPE"PLUMBING"
CDS_LIB"mstr_symbols"
BOM_COST"MEM_VRD_PVDDQ_CD";
"G\NAC"10;
%"GND"
"1","(-1300,2500)","0","mstr_symbols","I215";
;
HDL_POWER"GND"
VOLTAGE"0"
BODY_TYPE"PLUMBING"
CDS_LIB"mstr_symbols"
SIZE"1B"
BOM_COST"MEM_VRD_PVDDQ_CD"
ROOM"VDDQ_ABC_PWR_VR";
"A\NAC"11;
%"CAP_A"
"1","(2550,50)","0","dev_discrete","I216";
;
CDS_LOCATION"C5T5"
CDS_SEC"1"
$SEC"1"
ROOM"PVDDQ_ABC"
CDS_LIB"dev_discrete"
TOLERANCE"20%"
VOLTAGE"4V"
VALUE"22.0UF"
LOCATION"C5T5"
MATERIAL"X6S"
PACK_TYPE"0603V"
PART_NUMBER"E15431-004";
"B"
$PN"2"13;
"A"
$PN"1"12;
%"CAP_A"
"1","(2525,-650)","0","dev_discrete","I217";
;
CDS_SEC"1"
$SEC"1"
ROOM"PVDDQ_ABC"
CDS_LOCATION"C5G3"
CDS_LIB"dev_discrete"
MATERIAL"X6S"
VOLTAGE"4V"
PACK_TYPE"0603V"
TOLERANCE"20%"
VALUE"22.0UF"
PART_NUMBER"E15431-004"
LOCATION"C5G3";
"B"
$PN"2"15;
"A"
$PN"1"14;
%"CAP_A"
"1","(2275,50)","0","dev_discrete","I218";
;
CDS_SEC"1"
$SEC"1"
ROOM"PVDDQ_ABC"
CDS_LOCATION"C5T6"
CDS_LIB"dev_discrete"
VOLTAGE"4V"
VALUE"22.0UF"
LOCATION"C5T6"
TOLERANCE"20%"
PART_NUMBER"E15431-004"
MATERIAL"X6S"
PACK_TYPE"0603V";
"B"
$PN"2"13;
"A"
$PN"1"12;
%"CAP_A"
"1","(1975,50)","0","dev_discrete","I219";
;
CDS_SEC"1"
$SEC"1"
ROOM"PVDDQ_ABC"
CDS_LOCATION"C5T7"
CDS_LIB"dev_discrete"
LOCATION"C5T7"
VALUE"22.0UF"
VOLTAGE"4V"
TOLERANCE"20%"
PART_NUMBER"E15431-004"
PACK_TYPE"0603V"
MATERIAL"X6S";
"B"
$PN"2"13;
"A"
$PN"1"12;
%"CAP_A"
"1","(2250,-650)","0","dev_discrete","I220";
;
ROOM"PVDDQ_ABC"
$SEC"1"
CDS_SEC"1"
CDS_LOCATION"C5G15"
CDS_LIB"dev_discrete"
VALUE"22.0UF"
PART_NUMBER"E15431-004"
LOCATION"C5G15"
TOLERANCE"20%"
PACK_TYPE"0603V"
VOLTAGE"4V"
MATERIAL"X6S";
"B"
$PN"2"15;
"A"
$PN"1"14;
%"CAP_A"
"1","(1950,-650)","0","dev_discrete","I221";
;
CDS_SEC"1"
$SEC"1"
ROOM"PVDDQ_ABC"
CDS_LOCATION"C5G16"
CDS_LIB"dev_discrete"
LOCATION"C5G16"
PART_NUMBER"E15431-004"
VALUE"22.0UF"
TOLERANCE"20%"
PACK_TYPE"0603V"
VOLTAGE"4V"
MATERIAL"X6S";
"B"
$PN"2"15;
"A"
$PN"1"14;
%"CAP_A"
"1","(1675,50)","0","dev_discrete","I222";
;
CDS_SEC"1"
$SEC"1"
ROOM"PVDDQ_ABC"
CDS_LIB"dev_discrete"
CDS_LOCATION"C5T8"
LOCATION"C5T8"
VALUE"22.0UF"
VOLTAGE"4V"
TOLERANCE"20%"
MATERIAL"X6S"
PACK_TYPE"0603V"
PART_NUMBER"E15431-004";
"B"
$PN"2"13;
"A"
$PN"1"12;
%"CAP_A"
"1","(1650,-650)","0","dev_discrete","I223";
;
ROOM"PVDDQ_ABC"
SEC"1"
SEC_TYPE"0603V"
CDS_SEC"1"
CDS_LOCATION"C5G14"
CDS_LIB"dev_discrete"
LOCATION"C5G14"
PART_NUMBER"E15431-004"
VALUE"22.0UF"
PACK_TYPE"0603V"
MATERIAL"X6S"
VOLTAGE"4V"
TOLERANCE"20%";
"B"
$PN"2"15;
"A"
$PN"1"14;
%"CAP_A"
"1","(1400,50)","0","dev_discrete","I224";
;
CDS_SEC"1"
$SEC"1"
ROOM"PVDDQ_ABC"
CDS_LOCATION"C5T9"
CDS_LIB"dev_discrete"
LOCATION"C5T9"
VALUE"22.0UF"
VOLTAGE"4V"
TOLERANCE"20%"
PART_NUMBER"E15431-004"
PACK_TYPE"0603V"
MATERIAL"X6S";
"B"
$PN"2"13;
"A"
$PN"1"12;
%"CAP_A"
"1","(1125,50)","0","dev_discrete","I225";
;
CDS_SEC"1"
$SEC"1"
ROOM"PVDDQ_ABC"
CDS_LOCATION"C5T10"
CDS_LIB"dev_discrete"
LOCATION"C5T10"
VALUE"22.0UF"
VOLTAGE"4V"
TOLERANCE"20%"
PACK_TYPE"0603V"
PART_NUMBER"E15431-004"
MATERIAL"X6S";
"B"
$PN"2"13;
"A"
$PN"1"12;
%"CAP_A"
"1","(1375,-650)","0","dev_discrete","I226";
;
ROOM"PVDDQ_ABC"
$SEC"1"
CDS_SEC"1"
CDS_LOCATION"C5G17"
CDS_LIB"dev_discrete"
LOCATION"C5G17"
PART_NUMBER"E15431-004"
VALUE"22.0UF"
PACK_TYPE"0603V"
MATERIAL"X6S"
VOLTAGE"4V"
TOLERANCE"20%";
"B"
$PN"2"15;
"A"
$PN"1"14;
%"CAP_A"
"1","(1100,-650)","0","dev_discrete","I227";
;
ROOM"PVDDQ_ABC"
$SEC"1"
CDS_SEC"1"
CDS_LOCATION"C5G18"
CDS_LIB"dev_discrete"
LOCATION"C5G18"
PART_NUMBER"E15431-004"
VALUE"22.0UF"
PACK_TYPE"0603V"
MATERIAL"X6S"
VOLTAGE"4V"
TOLERANCE"20%";
"B"
$PN"2"15;
"A"
$PN"1"14;
%"CAP_A"
"1","(825,50)","0","dev_discrete","I228";
;
CDS_SEC"1"
$SEC"1"
ROOM"PVDDQ_ABC"
CDS_LOCATION"C5T11"
CDS_LIB"dev_discrete"
VALUE"22.0UF"
LOCATION"C5T11"
VOLTAGE"4V"
TOLERANCE"20%"
PART_NUMBER"E15431-004"
MATERIAL"X6S"
PACK_TYPE"0603V";
"B"
$PN"2"13;
"A"
$PN"1"12;
%"CAP_A"
"1","(525,50)","0","dev_discrete","I229";
;
CDS_SEC"1"
$SEC"1"
ROOM"PVDDQ_ABC"
CDS_LIB"dev_discrete"
CDS_LOCATION"C5T12"
LOCATION"C5T12"
VALUE"22.0UF"
VOLTAGE"4V"
TOLERANCE"20%"
PART_NUMBER"E15431-004"
MATERIAL"X6S"
PACK_TYPE"0603V";
"B"
$PN"2"13;
"A"
$PN"1"12;
%"CAP_A"
"1","(800,-650)","0","dev_discrete","I230";
;
ROOM"PVDDQ_ABC"
$SEC"1"
CDS_SEC"1"
CDS_LOCATION"C5G8"
CDS_LIB"dev_discrete"
PART_NUMBER"E15431-004"
VALUE"22.0UF"
MATERIAL"X6S"
VOLTAGE"4V"
TOLERANCE"20%"
LOCATION"C5G8"
PACK_TYPE"0603V";
"B"
$PN"2"15;
"A"
$PN"1"14;
%"CAP_A"
"1","(500,-650)","0","dev_discrete","I231";
;
SEC"1"
SEC_TYPE"0603V"
CDS_SEC"1"
ROOM"PVDDQ_ABC"
CDS_LOCATION"C5G1"
CDS_LIB"dev_discrete"
PART_NUMBER"E15431-004"
PACK_TYPE"0603V"
VOLTAGE"4V"
MATERIAL"X6S"
TOLERANCE"20%"
VALUE"22.0UF"
LOCATION"C5G1";
"B"
$PN"2"15;
"A"
$PN"1"14;
%"CAP_A"
"1","(200,50)","0","dev_discrete","I232";
;
$SEC"1"
CDS_SEC"1"
ROOM"PVDDQ_ABC"
CDS_LOCATION"C5U9"
CDS_LIB"dev_discrete"
VOLTAGE"4V"
VALUE"22.0UF"
LOCATION"C5U9"
TOLERANCE"20%"
PART_NUMBER"E15431-004"
MATERIAL"X6S"
PACK_TYPE"0603V";
"B"
$PN"2"13;
"A"
$PN"1"12;
%"CAP_A"
"1","(-75,50)","0","dev_discrete","I233";
;
CDS_SEC"1"
$SEC"1"
ROOM"PVDDQ_ABC"
CDS_LOCATION"C5U8"
CDS_LIB"dev_discrete"
LOCATION"C5U8"
PART_NUMBER"E15431-004"
VALUE"22.0UF"
TOLERANCE"20%"
PACK_TYPE"0603V"
VOLTAGE"4V"
MATERIAL"X6S";
"B"
$PN"2"13;
"A"
$PN"1"12;
%"CAP_A"
"1","(175,-650)","0","dev_discrete","I234";
;
ROOM"PVDDQ_ABC"
$SEC"1"
CDS_SEC"1"
CDS_LIB"dev_discrete"
CDS_LOCATION"C5G7"
PART_NUMBER"E15431-004"
LOCATION"C5G7"
VALUE"22.0UF"
TOLERANCE"20%"
PACK_TYPE"0603V"
MATERIAL"X6S"
VOLTAGE"4V";
"B"
$PN"2"15;
"A"
$PN"1"14;
%"CAP_A"
"1","(-100,-650)","0","dev_discrete","I235";
;
$SEC"1"
CDS_SEC"1"
ROOM"PVDDQ_ABC"
CDS_LOCATION"C5G5"
CDS_LIB"dev_discrete"
LOCATION"C5G5"
PART_NUMBER"E15431-004"
VALUE"22.0UF"
TOLERANCE"20%"
PACK_TYPE"0603V"
VOLTAGE"4V"
MATERIAL"X6S";
"B"
$PN"2"15;
"A"
$PN"1"14;
%"CAP_A"
"1","(-375,50)","0","dev_discrete","I236";
;
CDS_SEC"1"
$SEC"1"
ROOM"PVDDQ_ABC"
CDS_LIB"dev_discrete"
CDS_LOCATION"C5U7"
VALUE"22.0UF"
LOCATION"C5U7"
VOLTAGE"4V"
TOLERANCE"20%"
MATERIAL"X6S"
PACK_TYPE"0603V"
PART_NUMBER"E15431-004";
"B"
$PN"2"13;
"A"
$PN"1"12;
%"CAP_A"
"1","(-400,-650)","0","dev_discrete","I237";
;
ROOM"PVDDQ_ABC"
$SEC"1"
CDS_SEC"1"
CDS_LOCATION"C5G6"
CDS_LIB"dev_discrete"
LOCATION"C5G6"
PART_NUMBER"E15431-004"
VALUE"22.0UF"
PACK_TYPE"0603V"
MATERIAL"X6S"
VOLTAGE"4V"
TOLERANCE"20%";
"B"
$PN"2"15;
"A"
$PN"1"14;
%"CAP_A"
"1","(-675,50)","0","dev_discrete","I238";
;
CDS_SEC"1"
$SEC"1"
ROOM"PVDDQ_ABC"
CDS_LOCATION"C5U6"
CDS_LIB"dev_discrete"
LOCATION"C5U6"
VALUE"22.0UF"
VOLTAGE"4V"
TOLERANCE"20%"
PART_NUMBER"E15431-004"
PACK_TYPE"0603V"
MATERIAL"X6S";
"B"
$PN"2"13;
"A"
$PN"1"12;
%"CAP_A"
"1","(-950,50)","0","dev_discrete","I239";
;
CDS_SEC"1"
$SEC"1"
ROOM"PVDDQ_ABC"
CDS_LOCATION"C5U5"
CDS_LIB"dev_discrete"
VALUE"22.0UF"
LOCATION"C5U5"
VOLTAGE"4V"
TOLERANCE"20%"
PART_NUMBER"E15431-004"
PACK_TYPE"0603V"
MATERIAL"X6S";
"B"
$PN"2"13;
"A"
$PN"1"12;
%"CAP_A"
"1","(-700,-650)","0","dev_discrete","I240";
;
ROOM"PVDDQ_ABC"
SEC"1"
SEC_TYPE"0603V"
CDS_SEC"1"
CDS_LOCATION"C5G13"
CDS_LIB"dev_discrete"
LOCATION"C5G13"
PART_NUMBER"E15431-004"
VALUE"22.0UF"
PACK_TYPE"0603V"
MATERIAL"X6S"
VOLTAGE"4V"
TOLERANCE"20%";
"B"
$PN"2"15;
"A"
$PN"1"14;
%"CAP_A"
"1","(-975,-650)","0","dev_discrete","I241";
;
ROOM"PVDDQ_ABC"
$SEC"1"
CDS_SEC"1"
CDS_LOCATION"C5G4"
CDS_LIB"dev_discrete"
PART_NUMBER"E15431-004"
VALUE"22.0UF"
MATERIAL"X6S"
VOLTAGE"4V"
TOLERANCE"20%"
LOCATION"C5G4"
PACK_TYPE"0603V";
"B"
$PN"2"15;
"A"
$PN"1"14;
%"PVDDQ_ABC"
"1","(-1825,300)","0","mstr_symbols","I242";
;
VOLTAGE"1.2V"
BOM_COST"PROC_SOCKET "
CDS_LIB"mstr_symbols"
BODY_TYPE"PLUMBING"
ROOM"VDDQ_ABC_PWR_VR"
HDL_POWER"PVDDQ_ABC";
"G\NAC"12;
%"CAP_A"
"1","(-1225,50)","0","dev_discrete","I243";
;
CDS_SEC"1"
$SEC"1"
ROOM"PVDDQ_ABC"
CDS_LOCATION"C5U4"
CDS_LIB"dev_discrete"
VALUE"22.0UF"
LOCATION"C5U4"
VOLTAGE"4V"
TOLERANCE"20%"
PART_NUMBER"E15431-004"
MATERIAL"X6S"
PACK_TYPE"0603V";
"B"
$PN"2"13;
"A"
$PN"1"12;
%"CAP_A"
"1","(-1525,50)","0","dev_discrete","I244";
;
CDS_SEC"1"
$SEC"1"
ROOM"PVDDQ_ABC"
CDS_LIB"dev_discrete"
CDS_LOCATION"C5U3"
LOCATION"C5U3"
VALUE"22.0UF"
VOLTAGE"4V"
TOLERANCE"20%"
PART_NUMBER"E15431-004"
MATERIAL"X6S"
PACK_TYPE"0603V";
"B"
$PN"2"13;
"A"
$PN"1"12;
%"CAP_A"
"1","(-1250,-650)","0","dev_discrete","I245";
;
ROOM"PVDDQ_ABC"
$SEC"1"
CDS_SEC"1"
CDS_LOCATION"C5G2"
CDS_LIB"dev_discrete"
PART_NUMBER"E15431-004"
MATERIAL"X6S"
VOLTAGE"4V"
TOLERANCE"20%"
VALUE"22.0UF"
LOCATION"C5G2"
PACK_TYPE"0603V";
"B"
$PN"2"15;
"A"
$PN"1"14;
%"CAP_A"
"1","(-1550,-650)","0","dev_discrete","I246";
;
CDS_SEC"1"
$SEC"1"
ROOM"PVDDQ_ABC"
CDS_LOCATION"C5G12"
CDS_LIB"dev_discrete"
PART_NUMBER"E15431-004"
PACK_TYPE"0603V"
VOLTAGE"4V"
MATERIAL"X6S"
TOLERANCE"20%"
VALUE"22.0UF"
LOCATION"C5G12";
"B"
$PN"2"15;
"A"
$PN"1"14;
%"CAP_A"
"1","(-1825,50)","0","dev_discrete","I247";
;
ROOM"PVDDQ_ABC"
$SEC"1"
CDS_SEC"1"
CDS_LOCATION"C5U2"
CDS_LIB"dev_discrete"
LOCATION"C5U2"
VALUE"22.0UF"
VOLTAGE"4V"
TOLERANCE"20%"
PART_NUMBER"E15431-004"
PACK_TYPE"0603V"
MATERIAL"X6S";
"B"
$PN"2"13;
"A"
$PN"1"12;
%"GND"
"1","(-1825,-225)","0","mstr_symbols","I248";
;
SIZE"1B"
HDL_POWER"GND"
VOLTAGE"0"
CDS_LIB"mstr_symbols"
BODY_TYPE"PLUMBING"
ROOM"VDDQ_ABC_PWR_VR"
BOM_COST"PROC_VRD_VCCIN_CPU0";
"A\NAC"13;
%"PVDDQ_ABC"
"1","(-1850,-400)","0","mstr_symbols","I249";
;
ROOM"VDDQ_ABC_PWR_VR"
BOM_COST"PROC_SOCKET "
HDL_POWER"PVDDQ_ABC"
CDS_LIB"mstr_symbols"
BODY_TYPE"PLUMBING"
VOLTAGE"1.2V";
"G\NAC"14;
%"CAP_A"
"1","(-1850,-650)","0","dev_discrete","I250";
;
SEC_TYPE"0603V"
SEC"1"
CDS_SEC"1"
ROOM"PVDDQ_ABC"
CDS_LIB"dev_discrete"
CDS_LOCATION"C5G11"
PART_NUMBER"E15431-004"
LOCATION"C5G11"
VALUE"22.0UF"
TOLERANCE"20%"
PACK_TYPE"0603V"
VOLTAGE"4V"
MATERIAL"X6S";
"B"
$PN"2"15;
"A"
$PN"1"14;
%"GND"
"1","(-1850,-925)","0","mstr_symbols","I251";
;
SIZE"1B"
HDL_POWER"GND"
VOLTAGE"0"
CDS_LIB"mstr_symbols"
BODY_TYPE"PLUMBING"
ROOM"VDDQ_ABC_PWR_VR"
BOM_COST"PROC_VRD_VCCIN_CPU0";
"A\NAC"15;
%"SHUNT"
"1","(125,1500)","0","mstr_misc","I259";
;
CDS_SEC"1"
CDS_LOCATION"SH4U1"
SEC_TYPE"SH0201"
SEC"1"
CDS_LIB"mstr_misc"
MATERIAL"EMPTY"
PACK_TYPE"SH0201"
PIN_SHORT"A:B"
LOCATION"SH4U1"
PART_NUMBER"N_A";
"A"
$PN"1"23;
"B"
$PN"2"16;
%"SHUNT"
"1","(150,1950)","0","mstr_misc","I260";
;
CDS_SEC"1"
CDS_LOCATION"SH4U2"
SEC_TYPE"SH0201"
SEC"1"
CDS_LIB"mstr_misc"
MATERIAL"EMPTY"
PACK_TYPE"SH0201"
PIN_SHORT"A:B"
LOCATION"SH4U2"
PART_NUMBER"N_A";
"A"
$PN"1"22;
"B"
$PN"2"17;
%"RES"
"2","(4975,-475)","0","mstr_discrete","I58";
;
CDS_SEC"1"
$SEC"1"
CDS_LOCATION"R3U4"
BOM_COST"MEM_VRD_PVPP_AB"
ROOM"VDDQ_ABC_PWR_VR"
CDS_LIB"mstr_discrete"
LOCATION"R3U4"
PART_NUMBER"G22026-003"
VALUE"120.0"
PACK_TYPE"0603"
MATERIAL"CHIP"
WATTAGE"1/10W"
TOLERANCE"1%";
"A"
$PN"1"18;
"B"
$PN"2"19;
%"GND"
"1","(400,1275)","0","mstr_symbols","I65";
;
HDL_POWER"GND"
VOLTAGE"0"
CDS_LIB"mstr_symbols"
SIZE"1B"
BODY_TYPE"PLUMBING"
BOM_COST"MEM_VRD_PVPP_AB"
ROOM"VDDQ_ABC_PWR_VR";
"A\NAC"16;
%"PVDDQ_ABC"
"1","(425,2150)","0","mstr_symbols","I73";
;
ROOM"VDDQ_ABC_PWR_VR"
VOLTAGE"1.2V"
HDL_POWER"PVDDQ_ABC"
BODY_TYPE"PLUMBING"
CDS_LIB"mstr_symbols"
BOM_COST"MEM_VRD_PVPP_AB";
"G\NAC"17;
%"RES"
"2","(-250,1700)","0","mstr_discrete","I74";
;
CDS_SEC"1"
ROOM"VDDQ_ABC_PWR_VR"
CDS_LOCATION"R4U6"
SEC"1"
SEC_TYPE"0402"
CDS_LIB"mstr_discrete"
PART_NUMBER"G21796-017"
LOCATION"R4U6"
VALUE"100.0"
MATERIAL"EMPTY"
WATTAGE"1/16W"
TOLERANCE"1%"
PACK_TYPE"0402";
"A"
$PN"1"22;
"B"
$PN"2"23;
%"CAPP"
"1","(3375,-450)","0","mstr_discrete","I75";
;
CDS_SEC"1"
SEC"1"
SEC_TYPE"3018"
ROOM"VDDQ_ABC_PWR_VR"
CDS_LOCATION"C7G28"
CDS_LIB"mstr_discrete"
PART_NUMBER"699013-049"
LOCATION"C7G28"
VALUE"470UF"
TOLERANCE"20%"
VOLTAGE"2.5V"
PACK_TYPE"3018"
MATERIAL"ALUM";
"B"
$PN"2"19;
"A"
$PN"1"18;
%"CAPP"
"1","(3800,-450)","0","mstr_discrete","I76";
;
CDS_SEC"1"
ROOM"VDDQ_ABC_PWR_VR"
CDS_LOCATION"C3U1"
SEC"1"
SEC_TYPE"3018"
CDS_LIB"mstr_discrete"
PART_NUMBER"699013-049"
LOCATION"C3U1"
VALUE"470UF"
TOLERANCE"20%"
VOLTAGE"2.5V"
PACK_TYPE"3018"
MATERIAL"ALUM";
"B"
$PN"2"19;
"A"
$PN"1"18;
%"CAPP"
"1","(4225,-450)","0","mstr_discrete","I77";
;
CDS_SEC"1"
SEC"1"
SEC_TYPE"3018"
CDS_LOCATION"C3U5"
ROOM"VDDQ_ABC_PWR_VR"
CDS_LIB"mstr_discrete"
LOCATION"C3U5"
VALUE"470UF"
TOLERANCE"20%"
VOLTAGE"2.5V"
PART_NUMBER"699013-049"
PACK_TYPE"3018"
MATERIAL"ALUM";
"B"
$PN"2"19;
"A"
$PN"1"18;
%"CAPP"
"1","(4625,-475)","0","mstr_discrete","I78";
;
CDS_SEC"1"
SEC"1"
SEC_TYPE"3018"
ROOM"VDDQ_ABC_PWR_VR"
CDS_LOCATION"C3U8"
CDS_LIB"mstr_discrete"
LOCATION"C3U8"
VALUE"470UF"
TOLERANCE"20%"
VOLTAGE"2.5V"
PART_NUMBER"699013-049"
MATERIAL"ALUM"
PACK_TYPE"3018";
"B"
$PN"2"19;
"A"
$PN"1"18;
%"PVDDQ_ABC"
"1","(3375,-150)","0","mstr_symbols","I80";
;
ROOM"VDDQ_ABC_PWR_VR"
VOLTAGE"1.2V"
HDL_POWER"PVDDQ_ABC"
BODY_TYPE"PLUMBING"
CDS_LIB"mstr_symbols"
BOM_COST"MEM_VRD_PVPP_AB";
"G\NAC"18;
%"GND"
"1","(3375,-875)","0","mstr_symbols","I81";
;
HDL_POWER"GND"
VOLTAGE"0"
BODY_TYPE"PLUMBING"
SIZE"1B"
CDS_LIB"mstr_symbols"
BOM_COST"MEM_VRD_PVPP_AB"
ROOM"VDDQ_ABC_PWR_VR";
"A\NAC"19;
%"CAP"
"1","(5475,2850)","0","mstr_discrete","I82";
;
CDS_SEC"1"
SEC"1"
SEC_TYPE"0805"
BOM_COST"MEM_VRD_PVDDQ_CD"
CDS_LOCATION"C5U13"
ROOM"VDDQ_ABC_PWR_VR"
CDS_LIB"mstr_discrete"
LOCATION"C5U13"
PART_NUMBER"602433-112"
VALUE"100UF"
PACK_TYPE"0805"
VOLTAGE"4V"
TOLERANCE"20%"
MATERIAL"X5R";
"A"
$PN"1"20;
"B"
$PN"2"21;
%"CAP"
"1","(5075,2850)","0","mstr_discrete","I83";
;
CDS_SEC"1"
SEC"1"
SEC_TYPE"0805"
ROOM"VDDQ_ABC_PWR_VR"
CDS_LOCATION"C5U10"
BOM_COST"MEM_VRD_PVDDQ_CD"
CDS_LIB"mstr_discrete"
PART_NUMBER"602433-112"
LOCATION"C5U10"
VALUE"100UF"
TOLERANCE"20%"
PACK_TYPE"0805"
VOLTAGE"4V"
MATERIAL"X5R";
"A"
$PN"1"20;
"B"
$PN"2"21;
%"CAP"
"1","(4725,2850)","0","mstr_discrete","I88";
;
CDS_SEC"1"
SEC"1"
SEC_TYPE"0805"
BOM_COST"MEM_VRD_PVDDQ_CD"
CDS_LOCATION"C5U1"
ROOM"VDDQ_ABC_PWR_VR"
CDS_LIB"mstr_discrete"
LOCATION"C5U1"
PART_NUMBER"602433-112"
VALUE"100UF"
PACK_TYPE"0805"
VOLTAGE"4V"
TOLERANCE"20%"
MATERIAL"X5R";
"A"
$PN"1"20;
"B"
$PN"2"21;
%"CAP"
"1","(4325,2850)","0","mstr_discrete","I89";
;
CDS_SEC"1"
SEC"1"
SEC_TYPE"0805"
ROOM"VDDQ_ABC_PWR_VR"
CDS_LOCATION"C5U14"
BOM_COST"MEM_VRD_PVDDQ_CD"
CDS_LIB"mstr_discrete"
PART_NUMBER"602433-112"
LOCATION"C5U14"
VALUE"100UF"
MATERIAL"X5R"
VOLTAGE"4V"
PACK_TYPE"0805"
TOLERANCE"20%";
"A"
$PN"1"20;
"B"
$PN"2"21;
%"CAP"
"1","(3975,2850)","0","mstr_discrete","I90";
;
CDS_SEC"1"
SEC"1"
SEC_TYPE"0805"
BOM_COST"MEM_VRD_PVDDQ_CD"
CDS_LOCATION"C5U15"
ROOM"VDDQ_ABC_PWR_VR"
CDS_LIB"mstr_discrete"
LOCATION"C5U15"
PART_NUMBER"602433-112"
VALUE"100UF"
TOLERANCE"20%"
PACK_TYPE"0805"
MATERIAL"X5R"
VOLTAGE"4V";
"A"
$PN"1"20;
"B"
$PN"2"21;
%"CAP"
"1","(3625,2850)","0","mstr_discrete","I91";
;
CDS_SEC"1"
SEC"1"
SEC_TYPE"0805"
ROOM"VDDQ_ABC_PWR_VR"
CDS_LOCATION"C4T4"
BOM_COST"MEM_VRD_PVDDQ_CD"
CDS_LIB"mstr_discrete"
PART_NUMBER"602433-112"
LOCATION"C4T4"
VALUE"100UF"
VOLTAGE"4V"
TOLERANCE"20%"
MATERIAL"X5R"
PACK_TYPE"0805";
"A"
$PN"1"20;
"B"
$PN"2"21;
%"CAP"
"1","(3225,2850)","0","mstr_discrete","I92";
;
CDS_SEC"1"
SEC"1"
SEC_TYPE"0805"
BOM_COST"MEM_VRD_PVDDQ_CD"
CDS_LOCATION"C5G9"
ROOM"VDDQ_ABC_PWR_VR"
CDS_LIB"mstr_discrete"
LOCATION"C5G9"
PART_NUMBER"602433-112"
VALUE"100UF"
TOLERANCE"20%"
PACK_TYPE"0805"
VOLTAGE"4V"
MATERIAL"X5R";
"A"
$PN"1"20;
"B"
$PN"2"21;
%"PVDDQ_ABC"
"1","(2875,3125)","0","mstr_symbols","I93";
;
ROOM"VDDQ_ABC_PWR_VR"
VOLTAGE"1.2V"
HDL_POWER"PVDDQ_ABC"
BODY_TYPE"PLUMBING"
CDS_LIB"mstr_symbols"
BOM_COST"MEM_VRD_PVDDQ_CD";
"G\NAC"20;
%"GND"
"1","(4600,2475)","0","mstr_symbols","I94";
;
SIZE"1B"
HDL_POWER"GND"
BOM_COST"MEM_VRD_PVDDQ_CD"
VOLTAGE"0"
BODY_TYPE"PLUMBING"
CDS_LIB"mstr_symbols"
ROOM"VDDQ_ABC_PWR_VR";
"A\NAC"21;
END.
